FILE_TYPE = CONNECTIVITY;
{Allegro Design Entry HDL 16.6-p007 (v16-6-112F) 10/10/2012}
"PAGE_NUMBER" = 127;
0"NC";
1"GND\g";
2"P1V05_PCH_STBY\g";
3"GND\g";
4"P1V05_PCH_STBY\g";
5"GND\g";
6"GND\g";
7"GND\g";
8"P1V05_PCH_STBY_VCCA_XTAL\g"VOLTAGE"+1.05V";
9"P1V05_PCH_STBY_WM20_PLL\g"VOLTAGE"1.05V";
10"P1V05_PCH_STBY\g";
11"P1V05_PCH_STBY_WM26_PLL\g"VOLTAGE"1.05V";
12"GND\g";
13"P1V05_PCH_STBY_ISCLK_PLL\g"VOLTAGE"1.05V";
14"P1V05_PCH_STBY\g";
15"GND\g";
16"GND\g";
17"GND\g";
18"GND\g";
19"P1V05_PCH_STBY_KR_PLL\g"VOLTAGE"1.05V";
20"GND\g";
21"P1V05_PCH_STBY\g";
22"P1V05_PCH_STBY\g";
23"P1V05_PCH_STBY\g";
24"P1V05_PCH_STBY_VCCA_PLL0\g"VOLTAGE"+1.05V";
25"P1V05_PCH_STBY_VCCA_PLL1\g"VOLTAGE"+1.05V";
26"GND\g";
27"GND\g";
28"GND\g";
%"GND"
"1","(-3425,-2600)","0","mstr_symbols","I14";
;
VOLTAGE"0.0V"
HDL_POWER"GND"
CDS_LIB"mstr_symbols"
SIZE"1B"
BODY_TYPE"PLUMBING";
"A\NAC"1;
%"P1V05_PCH_STBY"
"1","(-4275,-1700)","0","mstr_symbols","I16";
;
VOLTAGE"1.05V"
HDL_POWER"P1V05_PCH_STBY"
CDS_LIB"mstr_symbols"
BODY_TYPE"PLUMBING";
"G\NAC"2;
%"FERRITE"
"1","(-4025,-2050)","0","mstr_discrete","I17";
;
CDS_SEC"1"
ROOM"SB_FILTER_PLL1"
BOM_COST"SB"
CDS_LIB"mstr_discrete"
SEC_TYPE"SM"
SEC"1"
CDS_LOCATION"FB3M2"
LOCATION"FB3M2"
PART_NUMBER"693286-027"
VALUE"120"
PACK_TYPE"SM"
MATERIAL"FB";
"A"
$PN"1"2;
"B"
$PN"2"24;
%"CAP_A"
"1","(-4275,-2250)","2","dev_discrete","I18";
;
ROOM"SB_FILTER_PLL1"
CDS_LOCATION"C3M22"
BOM_COST"SB"
CDS_LIB"dev_discrete"
CDS_SEC"1"
SEC_TYPE"0402V"
SEC"1"
LOCATION"C3M22"
PART_NUMBER"D97712-004"
VALUE"1.0UF"
TOLERANCE"10%"
PACK_TYPE"0402V"
VOLTAGE"6.3V"
MATERIAL"X6S";
"B"
$PN"2"1;
"A"
$PN"1"2;
%"GND"
"1","(-3400,-3900)","0","mstr_symbols","I23";
;
VOLTAGE"0.0V"
HDL_POWER"GND"
CDS_LIB"mstr_symbols"
SIZE"1B"
BODY_TYPE"PLUMBING";
"A\NAC"3;
%"P1V05_PCH_STBY"
"1","(-4250,-3000)","0","mstr_symbols","I25";
;
VOLTAGE"1.05V"
HDL_POWER"P1V05_PCH_STBY"
CDS_LIB"mstr_symbols"
BODY_TYPE"PLUMBING";
"G\NAC"4;
%"FERRITE"
"1","(-4000,-3350)","0","mstr_discrete","I26";
;
CDS_SEC"1"
ROOM"SB_FILTER_XTAL"
CDS_LIB"mstr_discrete"
BOM_COST"SB"
SEC_TYPE"SM"
SEC"1"
CDS_LOCATION"FB3M3"
LOCATION"FB3M3"
PART_NUMBER"693286-027"
VALUE"120"
PACK_TYPE"SM"
MATERIAL"FB";
"A"
$PN"1"4;
"B"
$PN"2"8;
%"CAP_A"
"1","(-4250,-3550)","2","dev_discrete","I27";
;
ROOM"SB_FILTER_XTAL"
CDS_LOCATION"C3M30"
BOM_COST"SB"
CDS_LIB"dev_discrete"
CDS_SEC"1"
SEC_TYPE"0402V"
SEC"1"
LOCATION"C3M30"
PART_NUMBER"D97712-004"
VALUE"1.0UF"
TOLERANCE"10%"
PACK_TYPE"0402V"
VOLTAGE"6.3V"
MATERIAL"X6S";
"B"
$PN"2"3;
"A"
$PN"1"4;
%"GND"
"1","(-2575,-1325)","0","mstr_symbols","I32";
;
VOLTAGE"0.0V"
HDL_POWER"GND"
CDS_LIB"mstr_symbols"
SIZE"1B"
BODY_TYPE"PLUMBING";
"A\NAC"5;
%"GND"
"1","(-2575,-2600)","0","mstr_symbols","I34";
;
VOLTAGE"0.0V"
HDL_POWER"GND"
SIZE"1B"
CDS_LIB"mstr_symbols"
BODY_TYPE"PLUMBING";
"A\NAC"6;
%"GND"
"1","(-2550,-3850)","0","mstr_symbols","I36";
;
VOLTAGE"0.0V"
HDL_POWER"GND"
CDS_LIB"mstr_symbols"
SIZE"1B"
BODY_TYPE"PLUMBING";
"A\NAC"7;
%"P1V05_PCH_STBY_VCCA_XTAL"
"1","(-2550,-2975)","0","mstr_symbols","I39";
;
VOLTAGE"1.05V"
HDL_POWER"P1V05_PCH_STBY_VCCA_XTAL"
ROOM"SB_DECOUPLING"
BOM_COST"SB"
CDS_LIB"mstr_symbols"
BODY_TYPE"PLUMBING";
"G\NAC"8;
%"P1V05_PCH_STBY_WM20_PLL"
"1","(1850,-750)","0","mstr_symbols","I40";
;
VOLTAGE"1.05V"
HDL_POWER"P1V05_PCH_STBY_WM20_PLL"
ROOM"SB_DECOUPLING"
BODY_TYPE"PLUMBING"
CDS_LIB"mstr_symbols"
BOM_COST"SB";
"G\NAC"9;
%"CAP"
"1","(1850,-1375)","0","mstr_discrete","I43";
;
CDS_SEC"1"
ROOM"SB_FILTER_VM20"
CDS_LIB"mstr_discrete"
BOM_COST"SB"
SEC_TYPE"0603LF"
SEC"1"
CDS_LOCATION"C2M5"
LOCATION"C2M5"
PART_NUMBER"E15431-001"
VALUE"10UF"
TOLERANCE"20%"
PACK_TYPE"0603LF"
VOLTAGE"4V"
MATERIAL"X6S";
"A"
$PN"1"9;
"B"
$PN"2"12;
%"CAP_A"
"1","(1400,-1375)","0","dev_discrete","I44";
;
ROOM"SB_FILTER_VM20"
CDS_LOCATION"C2M7"
BOM_COST"SB"
CDS_LIB"dev_discrete"
CDS_SEC"1"
SEC_TYPE"0402V"
SEC"1"
LOCATION"C2M7"
PART_NUMBER"D97712-004"
VALUE"1.0UF"
TOLERANCE"10%"
PACK_TYPE"0402V"
VOLTAGE"6.3V"
MATERIAL"X6S";
"B"
$PN"2"12;
"A"
$PN"1"9;
%"P1V05_PCH_STBY"
"1","(950,-825)","0","mstr_symbols","I45";
;
VOLTAGE"1.05V"
HDL_POWER"P1V05_PCH_STBY"
CDS_LIB"mstr_symbols"
BODY_TYPE"PLUMBING";
"G\NAC"10;
%"FERRITE"
"1","(1150,-1175)","0","mstr_discrete","I46";
;
CDS_SEC"1"
ROOM"SB_FILTER_VM20"
BOM_COST"SB"
SEC_TYPE"SM"
CDS_LIB"mstr_discrete"
SEC"1"
CDS_LOCATION"FB2M1"
LOCATION"FB2M1"
PART_NUMBER"693286-027"
VALUE"120"
PACK_TYPE"SM"
MATERIAL"FB";
"A"
$PN"1"10;
"B"
$PN"2"9;
%"P1V05_PCH_STBY_WM26_PLL"
"1","(-500,-800)","0","mstr_symbols","I47";
;
VOLTAGE"1.05V"
HDL_POWER"P1V05_PCH_STBY_WM26_PLL"
ROOM"SB_DECOUPLING"
BOM_COST"SB"
CDS_LIB"mstr_symbols"
BODY_TYPE"PLUMBING";
"G\NAC"11;
%"CAP"
"1","(-500,-1400)","0","mstr_discrete","I49";
;
CDS_SEC"1"
ROOM"SB_FILTER_VM26"
SEC_TYPE"0603LF"
BOM_COST"SB"
CDS_LIB"mstr_discrete"
SEC"1"
CDS_LOCATION"C2M10"
PART_NUMBER"E15431-001"
PACK_TYPE"0603LF"
TOLERANCE"20%"
LOCATION"C2M10"
VALUE"10UF"
VOLTAGE"4V"
MATERIAL"X6S";
"A"
$PN"1"11;
"B"
$PN"2"18;
%"CAP_A"
"1","(-1000,-1400)","0","dev_discrete","I50";
;
ROOM"SB_FILTER_VM26"
CDS_LOCATION"C2M9"
BOM_COST"SB"
CDS_LIB"dev_discrete"
CDS_SEC"1"
SEC_TYPE"0402V"
SEC"1"
LOCATION"C2M9"
PART_NUMBER"D97712-004"
VALUE"1.0UF"
TOLERANCE"10%"
PACK_TYPE"0402V"
VOLTAGE"6.3V"
MATERIAL"X6S";
"B"
$PN"2"18;
"A"
$PN"1"11;
%"GND"
"1","(1400,-1725)","0","mstr_symbols","I51";
;
VOLTAGE"0.0V"
HDL_POWER"GND"
CDS_LIB"mstr_symbols"
SIZE"1B"
BODY_TYPE"PLUMBING";
"A\NAC"12;
%"P1V05_PCH_STBY_ISCLK_PLL"
"1","(1700,-2700)","0","mstr_symbols","I52";
;
VOLTAGE"1.05V"
HDL_POWER"P1V05_PCH_STBY_ISCLK_PLL"
ROOM"SB_DECOUPLING"
BOM_COST"SB"
CDS_LIB"mstr_symbols"
BODY_TYPE"PLUMBING";
"G\NAC"13;
%"P1V05_PCH_STBY"
"1","(950,-2725)","0","mstr_symbols","I55";
;
VOLTAGE"1.05V"
HDL_POWER"P1V05_PCH_STBY"
CDS_LIB"mstr_symbols"
BODY_TYPE"PLUMBING";
"G\NAC"14;
%"FERRITE"
"1","(1150,-3075)","0","mstr_discrete","I56";
;
CDS_SEC"1"
ROOM"SB_FILTER_ISCLK"
BOM_COST"SB"
SEC_TYPE"SM"
CDS_LIB"mstr_discrete"
SEC"1"
CDS_LOCATION"FB3M4"
LOCATION"FB3M4"
PART_NUMBER"693286-027"
VALUE"120"
PACK_TYPE"SM"
MATERIAL"FB";
"A"
$PN"1"14;
"B"
$PN"2"13;
%"CAP_A"
"1","(950,-3275)","2","dev_discrete","I57";
;
ROOM"SB_FILTER_ISCLK"
CDS_LOCATION"C3M31"
BOM_COST"SB"
CDS_LIB"dev_discrete"
CDS_SEC"1"
SEC_TYPE"0402V"
SEC"1"
LOCATION"C3M31"
PART_NUMBER"D97712-004"
VALUE"1.0UF"
TOLERANCE"10%"
PACK_TYPE"0402V"
VOLTAGE"6.3V"
MATERIAL"X6S";
"B"
$PN"2"16;
"A"
$PN"1"14;
%"GND"
"1","(1700,-3625)","0","mstr_symbols","I58";
;
VOLTAGE"0.0V"
HDL_POWER"GND"
SIZE"1B"
CDS_LIB"mstr_symbols"
BODY_TYPE"PLUMBING";
"A\NAC"15;
%"GND"
"1","(950,-3675)","0","mstr_symbols","I59";
;
VOLTAGE"0.0V"
HDL_POWER"GND"
CDS_LIB"mstr_symbols"
SIZE"1B"
BODY_TYPE"PLUMBING";
"A\NAC"16;
%"GND"
"1","(-3450,-1400)","0","mstr_symbols","I6";
;
VOLTAGE"0.0V"
HDL_POWER"GND"
SIZE"1B"
CDS_LIB"mstr_symbols"
BODY_TYPE"PLUMBING";
"A\NAC"17;
%"GND"
"1","(-1000,-1750)","0","mstr_symbols","I61";
;
VOLTAGE"0.0V"
HDL_POWER"GND"
SIZE"1B"
CDS_LIB"mstr_symbols"
BODY_TYPE"PLUMBING";
"A\NAC"18;
%"P1V05_PCH_STBY_KR_PLL"
"1","(-500,-2650)","0","mstr_symbols","I62";
;
VOLTAGE"1.05V"
HDL_POWER"P1V05_PCH_STBY_KR_PLL"
ROOM"SB_DECOUPLING"
BODY_TYPE"PLUMBING"
CDS_LIB"mstr_symbols"
BOM_COST"SB";
"G\NAC"19;
%"CAP"
"1","(-500,-3300)","0","mstr_discrete","I64";
;
CDS_SEC"1"
ROOM"SB_FILTER_KR_PLL"
SEC_TYPE"0603LF"
BOM_COST"SB"
CDS_LIB"mstr_discrete"
SEC"1"
CDS_LOCATION"C2N6"
LOCATION"C2N6"
PART_NUMBER"E15431-001"
VALUE"10UF"
TOLERANCE"20%"
PACK_TYPE"0603LF"
VOLTAGE"4V"
MATERIAL"X6S";
"A"
$PN"1"19;
"B"
$PN"2"20;
%"CAP_A"
"1","(-1000,-3300)","0","dev_discrete","I65";
;
ROOM"SB_FILTER_KR_PLL"
CDS_LOCATION"C2N5"
BOM_COST"SB"
CDS_LIB"dev_discrete"
CDS_SEC"1"
SEC_TYPE"0402V"
SEC"1"
LOCATION"C2N5"
PART_NUMBER"D97712-004"
VALUE"1.0UF"
TOLERANCE"10%"
PACK_TYPE"0402V"
VOLTAGE"6.3V"
MATERIAL"X6S";
"B"
$PN"2"20;
"A"
$PN"1"19;
%"GND"
"1","(-500,-3650)","0","mstr_symbols","I66";
;
VOLTAGE"0.0V"
HDL_POWER"GND"
CDS_LIB"mstr_symbols"
SIZE"1B"
BODY_TYPE"PLUMBING";
"A\NAC"20;
%"P1V05_PCH_STBY"
"1","(-1450,-850)","0","mstr_symbols","I68";
;
VOLTAGE"1.05V"
HDL_POWER"P1V05_PCH_STBY"
CDS_LIB"mstr_symbols"
BODY_TYPE"PLUMBING";
"G\NAC"21;
%"FERRITE"
"1","(-1225,-1200)","0","mstr_discrete","I69";
;
CDS_SEC"1"
ROOM"SB_FILTER_VM26"
SEC_TYPE"SM"
BOM_COST"SB"
CDS_LIB"mstr_discrete"
SEC"1"
CDS_LOCATION"FB2M2"
LOCATION"FB2M2"
PART_NUMBER"693286-027"
VALUE"120"
PACK_TYPE"SM"
MATERIAL"FB";
"A"
$PN"1"21;
"B"
$PN"2"11;
%"P1V05_PCH_STBY"
"1","(-4300,-500)","0","mstr_symbols","I7";
;
VOLTAGE"1.05V"
HDL_POWER"P1V05_PCH_STBY"
CDS_LIB"mstr_symbols"
BODY_TYPE"PLUMBING";
"G\NAC"22;
%"P1V05_PCH_STBY"
"1","(-1450,-2725)","0","mstr_symbols","I70";
;
VOLTAGE"1.05V"
HDL_POWER"P1V05_PCH_STBY"
CDS_LIB"mstr_symbols"
BODY_TYPE"PLUMBING";
"G\NAC"23;
%"INDUCTOR"
"1","(-1250,-3100)","0","mstr_discrete","I71";
;
CDS_SEC"1"
ROOM"SB_FILTER_KR_PLL"
BOM_COST"SB"
CDS_LIB"mstr_discrete"
SEC_TYPE"SMT"
SEC"1"
CDS_LOCATION"L2M1"
VALUE"0.022UH"
LOCATION"L2M1"
PART_NUMBER"721891-082"
PACK_TYPE"SMT"
MATERIAL"IND";
"INA\NAC"
$PN"1"23;
"INB\NAC"
$PN"2"19;
%"P1V05_PCH_STBY_VCCA_PLL0"
"1","(-2575,-1675)","0","mstr_symbols","I72";
;
VOLTAGE"1.05V"
HDL_POWER"P1V05_PCH_STBY_VCCA_PLL0"
ROOM"SB_DECOUPLING"
BOM_COST"SB"
CDS_LIB"mstr_symbols"
BODY_TYPE"PLUMBING";
"G\NAC"24;
%"P1V05_PCH_STBY_VCCA_PLL1"
"1","(-2575,-475)","0","mstr_symbols","I73";
;
VOLTAGE"1.05V"
HDL_POWER"P1V05_PCH_STBY_VCCA_PLL1"
ROOM"SB_DECOUPLING"
BOM_COST"SB"
CDS_LIB"mstr_symbols"
BODY_TYPE"PLUMBING";
"G\NAC"25;
%"CAP_A"
"1","(-1450,-1400)","2","dev_discrete","I74";
;
ROOM"SB_FILTER_VM26"
CDS_LOCATION"C2M8"
BOM_COST"SB"
CDS_LIB"dev_discrete"
CDS_SEC"1"
SEC_TYPE"0402V"
SEC"1"
LOCATION"C2M8"
PART_NUMBER"D97712-004"
VALUE"1.0UF"
TOLERANCE"10%"
PACK_TYPE"0402V"
VOLTAGE"6.3V"
MATERIAL"X6S";
"B"
$PN"2"26;
"A"
$PN"1"21;
%"GND"
"1","(-1450,-1750)","0","mstr_symbols","I75";
;
VOLTAGE"0.0V"
HDL_POWER"GND"
CDS_LIB"mstr_symbols"
SIZE"1B"
BODY_TYPE"PLUMBING";
"A\NAC"26;
%"CAP_A"
"1","(950,-1375)","2","dev_discrete","I76";
;
ROOM"SB_FILTER_VM20"
CDS_LOCATION"C2M6"
BOM_COST"SB"
CDS_LIB"dev_discrete"
CDS_SEC"1"
SEC_TYPE"0402V"
SEC"1"
LOCATION"C2M6"
PART_NUMBER"D97712-004"
VALUE"1.0UF"
TOLERANCE"10%"
PACK_TYPE"0402V"
VOLTAGE"6.3V"
MATERIAL"X6S";
"B"
$PN"2"27;
"A"
$PN"1"10;
%"GND"
"1","(950,-1725)","0","mstr_symbols","I77";
;
VOLTAGE"0.0V"
HDL_POWER"GND"
SIZE"1B"
CDS_LIB"mstr_symbols"
BODY_TYPE"PLUMBING";
"A\NAC"27;
%"CAP_A"
"1","(-1450,-3300)","2","dev_discrete","I78";
;
CDS_LOCATION"C2M25"
ROOM"SB_FILTER_KR_PLL"
BOM_COST"SB"
CDS_LIB"dev_discrete"
CDS_SEC"1"
SEC_TYPE"0402V"
SEC"1"
MATERIAL"X6S"
LOCATION"C2M25"
PART_NUMBER"D97712-004"
VALUE"1.0UF"
TOLERANCE"10%"
PACK_TYPE"0402V"
VOLTAGE"6.3V";
"B"
$PN"2"28;
"A"
$PN"1"23;
%"GND"
"1","(-1450,-3625)","0","mstr_symbols","I79";
;
VOLTAGE"0.0V"
HDL_POWER"GND"
CDS_LIB"mstr_symbols"
SIZE"1B"
BODY_TYPE"PLUMBING";
"A\NAC"28;
%"FERRITE"
"1","(-4050,-850)","0","mstr_discrete","I8";
;
CDS_SEC"1"
ROOM"SB_FILTER_PLL0"
CDS_LIB"mstr_discrete"
BOM_COST"SB"
SEC_TYPE"SM"
SEC"1"
CDS_LOCATION"FB3M1"
LOCATION"FB3M1"
PART_NUMBER"693286-027"
VALUE"120"
PACK_TYPE"SM"
MATERIAL"FB";
"A"
$PN"1"22;
"B"
$PN"2"25;
%"CAP_A"
"1","(1400,-3275)","0","dev_discrete","I80";
;
ROOM"SB_FILTER_ISCLK"
SEC"1"
SEC_TYPE"0402V"
CDS_SEC"1"
CDS_LIB"dev_discrete"
BOM_COST"SB"
CDS_LOCATION"C3M29"
LOCATION"C3M29"
PART_NUMBER"D97712-004"
VALUE"1.0UF"
TOLERANCE"10%"
PACK_TYPE"0402V"
VOLTAGE"6.3V"
MATERIAL"X6S";
"B"
$PN"2"16;
"A"
$PN"1"13;
%"CAP"
"1","(1700,-3275)","0","mstr_discrete","I81";
;
ROOM"SB_FILTER_ISCLK"
CDS_SEC"1"
BOM_COST"SB"
SEC_TYPE"0603LF"
CDS_LIB"mstr_discrete"
SEC"1"
CDS_LOCATION"C3M24"
LOCATION"C3M24"
PART_NUMBER"E15431-001"
VALUE"10UF"
TOLERANCE"20%"
PACK_TYPE"0603LF"
VOLTAGE"4V"
MATERIAL"X6S";
"A"
$PN"1"13;
"B"
$PN"2"15;
%"CAP"
"1","(-2550,-3600)","0","mstr_discrete","I82";
;
ROOM"SB_FILTER_XTAL"
CDS_SEC"1"
BOM_COST"SB"
CDS_LIB"mstr_discrete"
SEC_TYPE"0603LF"
SEC"1"
CDS_LOCATION"C3M23"
LOCATION"C3M23"
PART_NUMBER"E15431-001"
VALUE"10UF"
TOLERANCE"20%"
PACK_TYPE"0603LF"
VOLTAGE"4V"
MATERIAL"X6S";
"A"
$PN"1"8;
"B"
$PN"2"7;
%"CAP_A"
"1","(-3400,-3550)","0","dev_discrete","I83";
;
ROOM"SB_FILTER_XTAL"
CDS_LOCATION"C3M27"
BOM_COST"SB"
CDS_LIB"dev_discrete"
CDS_SEC"1"
SEC_TYPE"0402V"
SEC"1"
LOCATION"C3M27"
PART_NUMBER"D97712-004"
VALUE"1.0UF"
TOLERANCE"10%"
PACK_TYPE"0402V"
VOLTAGE"6.3V"
MATERIAL"X6S";
"B"
$PN"2"3;
"A"
$PN"1"8;
%"CAP_A"
"1","(-3425,-2250)","0","dev_discrete","I84";
;
ROOM"SB_FILTER_PLL1"
SEC"1"
SEC_TYPE"0402V"
CDS_SEC"1"
CDS_LIB"dev_discrete"
BOM_COST"SB"
CDS_LOCATION"C3M20"
MATERIAL"X6S"
LOCATION"C3M20"
PART_NUMBER"D97712-004"
VALUE"1.0UF"
TOLERANCE"10%"
PACK_TYPE"0402V"
VOLTAGE"6.3V";
"B"
$PN"2"1;
"A"
$PN"1"24;
%"CAP"
"1","(-2575,-2325)","0","mstr_discrete","I85";
;
ROOM"SB_FILTER_PLL1"
CDS_SEC"1"
CDS_LIB"mstr_discrete"
BOM_COST"SB"
SEC_TYPE"0603LF"
SEC"1"
CDS_LOCATION"C3M18"
LOCATION"C3M18"
PART_NUMBER"E15431-001"
VALUE"10UF"
TOLERANCE"20%"
PACK_TYPE"0603LF"
VOLTAGE"4V"
MATERIAL"X6S";
"A"
$PN"1"24;
"B"
$PN"2"6;
%"CAP"
"1","(-2575,-1075)","0","mstr_discrete","I86";
;
ROOM"SB_FILTER_PLL0"
CDS_LOCATION"C3M17"
SEC"1"
SEC_TYPE"0603LF"
CDS_LIB"mstr_discrete"
BOM_COST"SB"
CDS_SEC"1"
LOCATION"C3M17"
PART_NUMBER"E15431-001"
VALUE"10UF"
TOLERANCE"20%"
PACK_TYPE"0603LF"
VOLTAGE"4V"
MATERIAL"X6S";
"A"
$PN"1"25;
"B"
$PN"2"5;
%"CAP_A"
"1","(-3450,-1050)","0","dev_discrete","I87";
;
ROOM"SB_FILTER_PLL0"
SEC"1"
SEC_TYPE"0402V"
CDS_SEC"1"
CDS_LIB"dev_discrete"
BOM_COST"SB"
CDS_LOCATION"C3M19"
LOCATION"C3M19"
PART_NUMBER"D97712-004"
VALUE"1.0UF"
TOLERANCE"10%"
PACK_TYPE"0402V"
VOLTAGE"6.3V"
MATERIAL"X6S";
"B"
$PN"2"17;
"A"
$PN"1"25;
%"CAP_A"
"1","(-4300,-1050)","2","dev_discrete","I9";
;
ROOM"SB_FILTER_PLL0"
CDS_LOCATION"C3M21"
BOM_COST"SB"
CDS_LIB"dev_discrete"
CDS_SEC"1"
SEC_TYPE"0402V"
SEC"1"
LOCATION"C3M21"
PART_NUMBER"D97712-004"
VALUE"1.0UF"
TOLERANCE"10%"
PACK_TYPE"0402V"
VOLTAGE"6.3V"
MATERIAL"X6S";
"B"
$PN"2"17;
"A"
$PN"1"22;
END.
